# T6G (Grand Teton) — schematic netlist excerpt (pin names and nets, part order shuffled) for the footprints in the layout excerpt that follows; sources: Cadence DE-HDL packaged netlist, KiCad conversion of 04192023_DAF0TMB3IC0_F0TG_MB_C_brd_V02_OCP.brd

PR427  Q_RES  2.2 1% CHIP  pkg 0402LF  page 220 : A = PVDDCR_CPU1_P1_PVCC ; B = PVDDCR_CPU1_P1_VCC6
R2846  Q_RES  33.2 1% CHIP  pkg 0402LF  page 81 : A = BIC_MONITER_ISO_R ; B = BIC_MONITER_ISO

(kicad_pcb
	(version 20260206)
	(generator "pcbnew")
	(generator_version "10.0")
	(general
		(thickness 1.6)
		(legacy_teardrops no)
	)
	(paper "A4")
	(title_block
		(title "04192023_DAF0TMB3IC0_F0TG_MB_C_brd_V02_OCP.brd")
		(comment 1 "Grand Teton / footprints 5720-5721 of 8354")
	)
	(layers
		(0 "F.Cu" signal "TOP")
		(4 "In1.Cu" signal "GND")
		(6 "In2.Cu" signal "IN1")
		(8 "In3.Cu" signal "GND1")
		(10 "In4.Cu" signal "IN2")
		(12 "In5.Cu" signal "GND2")
		(14 "In6.Cu" signal "IN3")
		(16 "In7.Cu" signal "GND3")
		(18 "In8.Cu" signal "VCC")
		(20 "In9.Cu" signal "VCC1")
		(22 "In10.Cu" signal "GND4")
		(24 "In11.Cu" signal "IN4")
		(26 "In12.Cu" signal "GND5")
		(28 "In13.Cu" signal "IN5")
		(30 "In14.Cu" signal "GND6")
		(32 "In15.Cu" signal "IN6")
		(34 "In16.Cu" signal "GND7")
		(2 "B.Cu" signal "BOTTOM")
		(9 "F.Adhes" user "F.Adhesive")
		(11 "B.Adhes" user "B.Adhesive")
		(13 "F.Paste" user "Package Geometry/Pastemask Top")
		(15 "B.Paste" user "Package Geometry/Pastemask Bottom")
		(5 "F.SilkS" user "Ref Des/Silkscreen Top")
		(7 "B.SilkS" user "Ref Des/Silkscreen Bottom")
		(1 "F.Mask" user "Board Geometry/Soldermask Top")
		(3 "B.Mask" user "Board Geometry/Soldermask Bottom")
		(17 "Dwgs.User" user "User.Drawings")
		(19 "Cmts.User" user "User.Comments")
		(21 "Eco1.User" user "User.Eco1")
		(23 "Eco2.User" user "User.Eco2")
		(25 "Edge.Cuts" user "Board Geometry/Outline")
		(27 "Margin" user)
		(31 "F.CrtYd" user "Package Geometry/Place Bound Top")
		(29 "B.CrtYd" user "Package Geometry/Place Bound Bottom")
		(35 "F.Fab" user "Ref Des/Assembly Top")
		(33 "B.Fab" user "Ref Des/Assembly Bottom")
	)
	(footprint ""
		(layer "B.Cu")
		(at 101.41839 -340.998556 -90)
		(property "Reference" "PR427"
			(at 0 0 90)
			(layer "B.SilkS")
			(hide yes)
			(effects
				(font
					(size 1.27 1.27)
				)
				(justify mirror)
			)
		)
		(property "Value" ""
			(at 0 0 90)
			(layer "B.Fab")
			(effects
				(font
					(size 1.27 1.27)
				)
				(justify mirror)
			)
		)
		(duplicate_pad_numbers_are_jumpers no)
		(fp_line
			(start -0.7874 0.4064)
			(end 0.7874 0.4064)
			(stroke
				(width 0.1524)
				(type default)
			)
			(layer "B.SilkS")
		)
		(fp_line
			(start 0.7874 0.4064)
			(end 0.7874 -0.4064)
			(stroke
				(width 0.1524)
				(type default)
			)
			(layer "B.SilkS")
		)
		(fp_line
			(start -0.7874 -0.4064)
			(end -0.7874 0.4064)
			(stroke
				(width 0.1524)
				(type default)
			)
			(layer "B.SilkS")
		)
		(fp_line
			(start 0.7874 -0.4064)
			(end -0.7874 -0.4064)
			(stroke
				(width 0.1524)
				(type default)
			)
			(layer "B.SilkS")
		)
		(fp_line
			(start -0.67945 0.3048)
			(end -0.120396 0.3048)
			(stroke
				(width 0.1)
				(type default)
			)
			(layer "B.Fab")
		)
		(fp_line
			(start -0.120396 0.3048)
			(end -0.120396 0.2794)
			(stroke
				(width 0.1)
				(type default)
			)
			(layer "B.Fab")
		)
		(fp_line
			(start 0.12065 0.3048)
			(end 0.67945 0.3048)
			(stroke
				(width 0.1)
				(type default)
			)
			(layer "B.Fab")
		)
		(fp_line
			(start 0.67945 0.3048)
			(end 0.67945 -0.305054)
			(stroke
				(width 0.1)
				(type default)
			)
			(layer "B.Fab")
		)
		(fp_line
			(start -0.120396 0.2794)
			(end 0.12065 0.2794)
			(stroke
				(width 0.1)
				(type default)
			)
			(layer "B.Fab")
		)
		(fp_line
			(start 0.12065 0.2794)
			(end 0.12065 0.3048)
			(stroke
				(width 0.1)
				(type default)
			)
			(layer "B.Fab")
		)
		(fp_line
			(start -0.12065 -0.2794)
			(end -0.12065 -0.3048)
			(stroke
				(width 0.1)
				(type default)
			)
			(layer "B.Fab")
		)
		(fp_line
			(start 0.12065 -0.2794)
			(end -0.12065 -0.2794)
			(stroke
				(width 0.1)
				(type default)
			)
			(layer "B.Fab")
		)
		(fp_line
			(start -0.67945 -0.3048)
			(end -0.67945 0.3048)
			(stroke
				(width 0.1)
				(type default)
			)
			(layer "B.Fab")
		)
		(fp_line
			(start -0.12065 -0.3048)
			(end -0.67945 -0.3048)
			(stroke
				(width 0.1)
				(type default)
			)
			(layer "B.Fab")
		)
		(fp_line
			(start 0.12065 -0.305054)
			(end 0.12065 -0.2794)
			(stroke
				(width 0.1)
				(type default)
			)
			(layer "B.Fab")
		)
		(fp_line
			(start 0.67945 -0.305054)
			(end 0.12065 -0.305054)
			(stroke
				(width 0.1)
				(type default)
			)
			(layer "B.Fab")
		)
		(pad "1" smd circle
			(at 0.40005 0 90)
			(size 0 0)
			(layers "B.Cu" "B.Mask" "B.Paste")
			(net "PVDDCR_CPU1_P1_PVCC")
		)
		(pad "2" smd circle
			(at -0.40005 0 90)
			(size 0 0)
			(layers "B.Cu" "B.Mask" "B.Paste")
			(net "PVDDCR_CPU1_P1_VCC6")
		)
	)
	(footprint ""
		(layer "B.Cu")
		(at 200.023222 -123.831096 180)
		(property "Reference" "R2846"
			(at 0 0 0)
			(layer "B.SilkS")
			(hide yes)
			(effects
				(font
					(size 1.27 1.27)
				)
				(justify mirror)
			)
		)
		(property "Value" ""
			(at 0 0 0)
			(layer "B.Fab")
			(effects
				(font
					(size 1.27 1.27)
				)
				(justify mirror)
			)
		)
		(duplicate_pad_numbers_are_jumpers no)
		(fp_line
			(start 0.7874 0.4064)
			(end 0.7874 -0.4064)
			(stroke
				(width 0.1524)
				(type default)
			)
			(layer "B.SilkS")
		)
		(fp_line
			(start 0.7874 -0.4064)
			(end -0.7874 -0.4064)
			(stroke
				(width 0.1524)
				(type default)
			)
			(layer "B.SilkS")
		)
		(fp_line
			(start -0.7874 0.4064)
			(end 0.7874 0.4064)
			(stroke
				(width 0.1524)
				(type default)
			)
			(layer "B.SilkS")
		)
		(fp_line
			(start -0.7874 -0.4064)
			(end -0.7874 0.4064)
			(stroke
				(width 0.1524)
				(type default)
			)
			(layer "B.SilkS")
		)
		(fp_line
			(start 0.67945 0.3048)
			(end 0.67945 -0.305054)
			(stroke
				(width 0.1)
				(type default)
			)
			(layer "B.Fab")
		)
		(fp_line
			(start 0.67945 -0.305054)
			(end 0.12065 -0.305054)
			(stroke
				(width 0.1)
				(type default)
			)
			(layer "B.Fab")
		)
		(fp_line
			(start 0.12065 0.3048)
			(end 0.67945 0.3048)
			(stroke
				(width 0.1)
				(type default)
			)
			(layer "B.Fab")
		)
		(fp_line
			(start 0.12065 0.2794)
			(end 0.12065 0.3048)
			(stroke
				(width 0.1)
				(type default)
			)
			(layer "B.Fab")
		)
		(fp_line
			(start 0.12065 -0.2794)
			(end -0.12065 -0.2794)
			(stroke
				(width 0.1)
				(type default)
			)
			(layer "B.Fab")
		)
		(fp_line
			(start 0.12065 -0.305054)
			(end 0.12065 -0.2794)
			(stroke
				(width 0.1)
				(type default)
			)
			(layer "B.Fab")
		)
		(fp_line
			(start -0.120396 0.3048)
			(end -0.120396 0.2794)
			(stroke
				(width 0.1)
				(type default)
			)
			(layer "B.Fab")
		)
		(fp_line
			(start -0.120396 0.2794)
			(end 0.12065 0.2794)
			(stroke
				(width 0.1)
				(type default)
			)
			(layer "B.Fab")
		)
		(fp_line
			(start -0.12065 -0.2794)
			(end -0.12065 -0.3048)
			(stroke
				(width 0.1)
				(type default)
			)
			(layer "B.Fab")
		)
		(fp_line
			(start -0.12065 -0.3048)
			(end -0.67945 -0.3048)
			(stroke
				(width 0.1)
				(type default)
			)
			(layer "B.Fab")
		)
		(fp_line
			(start -0.67945 0.3048)
			(end -0.120396 0.3048)
			(stroke
				(width 0.1)
				(type default)
			)
			(layer "B.Fab")
		)
		(fp_line
			(start -0.67945 -0.3048)
			(end -0.67945 0.3048)
			(stroke
				(width 0.1)
				(type default)
			)
			(layer "B.Fab")
		)
		(pad "1" smd circle
			(at 0.40005 0)
			(size 0 0)
			(layers "B.Cu" "B.Mask" "B.Paste")
			(net "BIC_MONITER_ISO_R")
		)
		(pad "2" smd circle
			(at -0.40005 0)
			(size 0 0)
			(layers "B.Cu" "B.Mask" "B.Paste")
			(net "BIC_MONITER_ISO")
		)
	)
)
